(kicad_pcb
	(version 20260206)
	(generator "pcbnew")
	(generator_version "10.0")
	(general
		(thickness 1.6)
		(legacy_teardrops no)
	)
	(paper "A4")
	(title_block
		(title "Bryce Canyon_IOM_M2_16342-2_OCP.brd")
		(comment 1 "Bryce Canyon / footprints 1139-1145 of 1146")
	)
	(layers
		(0 "F.Cu" signal "TOP")
		(4 "In1.Cu" signal "L2GND")
		(6 "In2.Cu" signal "L3")
		(8 "In3.Cu" signal "L4VCC")
		(10 "In4.Cu" signal "L5VCC")
		(12 "In5.Cu" signal "L6")
		(14 "In6.Cu" signal "L7GND")
		(2 "B.Cu" signal "BOTTOM")
		(9 "F.Adhes" user "F.Adhesive")
		(11 "B.Adhes" user "B.Adhesive")
		(13 "F.Paste" user "Package Geometry/Pastemask Top")
		(15 "B.Paste" user "Package Geometry/Pastemask Bottom")
		(5 "F.SilkS" user "Ref Des/Silkscreen Top")
		(7 "B.SilkS" user "Ref Des/Silkscreen Bottom")
		(1 "F.Mask" user "Board Geometry/Soldermask Top")
		(3 "B.Mask" user "Board Geometry/Soldermask Bottom")
		(17 "Dwgs.User" user "User.Drawings")
		(19 "Cmts.User" user "User.Comments")
		(21 "Eco1.User" user "User.Eco1")
		(23 "Eco2.User" user "User.Eco2")
		(25 "Edge.Cuts" user "Board Geometry/Outline")
		(27 "Margin" user)
		(31 "F.CrtYd" user "Package Geometry/Place Bound Top")
		(29 "B.CrtYd" user "Package Geometry/Place Bound Bottom")
		(35 "F.Fab" user "Ref Des/Assembly Top")
		(33 "B.Fab" user "Ref Des/Assembly Bottom")
	)
	(footprint ""
		(layer "B.Cu")
		(at 55.372 -132.08)
		(property "Reference" "C114"
			(at 0 0 0)
			(layer "B.SilkS")
			(hide yes)
			(effects
				(font
					(size 1.27 1.27)
				)
				(justify mirror)
			)
		)
		(property "Value" "SC1U16V3KX-5GP"
			(at 0 -2.8194 0)
			(unlocked yes)
			(layer "B.Fab")
			(hide yes)
			(effects
				(font
					(size 1.016 1.016)
					(thickness 0.1524)
				)
				(justify mirror)
			)
		)
		(property "Device Type" "C603H36"
			(at 0 -4.3434 0)
			(unlocked yes)
			(layer "B.Fab")
			(hide yes)
			(effects
				(font
					(size 1.016 1.016)
					(thickness 0.1524)
				)
				(justify mirror)
			)
		)
		(duplicate_pad_numbers_are_jumpers no)
		(fp_line
			(start -0.508 0)
			(end 0.508 0)
			(stroke
				(width 0.2032)
				(type default)
			)
			(layer "B.SilkS")
		)
		(fp_rect
			(start 0.5842 1.3335)
			(end -0.5842 -1.3335)
			(stroke
				(width 0)
				(type default)
			)
			(fill no)
			(layer "B.CrtYd")
		)
		(fp_rect
			(start 0.5842 1.3335)
			(end -0.5842 -1.3335)
			(stroke
				(width 0)
				(type default)
			)
			(fill no)
			(layer "B.Fab")
		)
		(pad "1" smd custom
			(at 0 -0.762 180)
			(size 0.2159 0.2159)
			(layers "B.Cu" "B.Mask" "B.Paste")
			(net "P1V15_STBY")
			(options
				(clearance outline)
				(anchor circle)
			)
			(primitives
				(gr_poly
					(pts
						(arc
							(start -0.3302 0.4318)
							(mid -0.402042 0.402042)
							(end -0.4318 0.3302)
						)
						(arc
							(start -0.4318 -0.3302)
							(mid -0.402042 -0.402042)
							(end -0.3302 -0.4318)
						)
						(arc
							(start 0.3302 -0.4318)
							(mid 0.402042 -0.402042)
							(end 0.4318 -0.3302)
						)
						(arc
							(start 0.4318 0.3302)
							(mid 0.402042 0.402042)
							(end 0.3302 0.4318)
						)
					)
					(width 0)
					(fill yes)
				)
			)
		)
		(pad "2" smd custom
			(at 0 0.762 180)
			(size 0.2159 0.2159)
			(layers "B.Cu" "B.Mask" "B.Paste")
			(net "GND")
			(options
				(clearance outline)
				(anchor circle)
			)
			(primitives
				(gr_poly
					(pts
						(arc
							(start -0.3302 0.4318)
							(mid -0.402042 0.402042)
							(end -0.4318 0.3302)
						)
						(arc
							(start -0.4318 -0.3302)
							(mid -0.402042 -0.402042)
							(end -0.3302 -0.4318)
						)
						(arc
							(start 0.3302 -0.4318)
							(mid 0.402042 -0.402042)
							(end 0.4318 -0.3302)
						)
						(arc
							(start 0.4318 0.3302)
							(mid 0.402042 0.402042)
							(end 0.3302 0.4318)
						)
					)
					(width 0)
					(fill yes)
				)
			)
		)
	)
	(footprint ""
		(layer "B.Cu")
		(at 54.229 -161.163 90)
		(property "Reference" "R404"
			(at 0 0 90)
			(layer "B.SilkS")
			(hide yes)
			(effects
				(font
					(size 1.27 1.27)
				)
				(justify mirror)
			)
		)
		(property "Value" "1KR2F-3-GP"
			(at -0.064008 -3.993896 90)
			(unlocked yes)
			(layer "B.Fab")
			(hide yes)
			(effects
				(font
					(size 1.016 1.016)
					(thickness 0.1524)
				)
				(justify mirror)
			)
		)
		(property "Device Type" "R402H16"
			(at -0.064008 -5.517896 90)
			(unlocked yes)
			(layer "B.Fab")
			(hide yes)
			(effects
				(font
					(size 1.016 1.016)
					(thickness 0.1524)
				)
				(justify mirror)
			)
		)
		(duplicate_pad_numbers_are_jumpers no)
		(fp_line
			(start 0.508 -0.9398)
			(end 0.508 0.9398)
			(stroke
				(width 0.1524)
				(type default)
			)
			(layer "B.SilkS")
		)
		(fp_line
			(start -0.508 -0.9398)
			(end 0.508 -0.9398)
			(stroke
				(width 0.1524)
				(type default)
			)
			(layer "B.SilkS")
		)
		(fp_rect
			(start 0.508 0.9398)
			(end -0.508 -0.9398)
			(stroke
				(width 0)
				(type default)
			)
			(fill no)
			(layer "B.CrtYd")
		)
		(fp_rect
			(start 0.508 0.9398)
			(end -0.508 -0.9398)
			(stroke
				(width 0)
				(type default)
			)
			(fill no)
			(layer "B.Fab")
		)
		(pad "1" smd custom
			(at 0 -0.4445 270)
			(size 0.1397 0.1397)
			(layers "B.Cu" "B.Mask" "B.Paste")
			(net "ADC_12V")
			(options
				(clearance outline)
				(anchor circle)
			)
			(primitives
				(gr_poly
					(pts
						(arc
							(start -0.1778 0.2794)
							(mid -0.249642 0.249642)
							(end -0.2794 0.1778)
						)
						(arc
							(start -0.2794 -0.1778)
							(mid -0.249642 -0.249642)
							(end -0.1778 -0.2794)
						)
						(arc
							(start 0.1778 -0.2794)
							(mid 0.249642 -0.249642)
							(end 0.2794 -0.1778)
						)
						(arc
							(start 0.2794 0.1778)
							(mid 0.249642 0.249642)
							(end 0.1778 0.2794)
						)
					)
					(width 0)
					(fill yes)
				)
			)
		)
		(pad "2" smd custom
			(at 0 0.4445 270)
			(size 0.1397 0.1397)
			(layers "B.Cu" "B.Mask" "B.Paste")
			(net "GND")
			(options
				(clearance outline)
				(anchor circle)
			)
			(primitives
				(gr_poly
					(pts
						(arc
							(start -0.1778 0.2794)
							(mid -0.249642 0.249642)
							(end -0.2794 0.1778)
						)
						(arc
							(start -0.2794 -0.1778)
							(mid -0.249642 -0.249642)
							(end -0.1778 -0.2794)
						)
						(arc
							(start 0.1778 -0.2794)
							(mid 0.249642 -0.249642)
							(end 0.2794 -0.1778)
						)
						(arc
							(start 0.2794 0.1778)
							(mid 0.249642 0.249642)
							(end 0.1778 0.2794)
						)
					)
					(width 0)
					(fill yes)
				)
			)
		)
	)
	(footprint ""
		(layer "B.Cu")
		(at 56.4134 -121.1326)
		(property "Reference" "R285"
			(at 0 0 0)
			(layer "B.SilkS")
			(hide yes)
			(effects
				(font
					(size 1.27 1.27)
				)
				(justify mirror)
			)
		)
		(property "Value" "4K7R2F-GP"
			(at -0.064008 -3.993896 0)
			(unlocked yes)
			(layer "B.Fab")
			(hide yes)
			(effects
				(font
					(size 1.016 1.016)
					(thickness 0.1524)
				)
				(justify mirror)
			)
		)
		(property "Device Type" "R402H16"
			(at -0.064008 -5.517896 0)
			(unlocked yes)
			(layer "B.Fab")
			(hide yes)
			(effects
				(font
					(size 1.016 1.016)
					(thickness 0.1524)
				)
				(justify mirror)
			)
		)
		(duplicate_pad_numbers_are_jumpers no)
		(fp_line
			(start -0.508 -0.9398)
			(end 0.508 -0.9398)
			(stroke
				(width 0.1524)
				(type default)
			)
			(layer "B.SilkS")
		)
		(fp_line
			(start 0.508 -0.9398)
			(end 0.508 0.9398)
			(stroke
				(width 0.1524)
				(type default)
			)
			(layer "B.SilkS")
		)
		(fp_rect
			(start 0.508 0.9398)
			(end -0.508 -0.9398)
			(stroke
				(width 0)
				(type default)
			)
			(fill no)
			(layer "B.CrtYd")
		)
		(fp_rect
			(start 0.508 0.9398)
			(end -0.508 -0.9398)
			(stroke
				(width 0)
				(type default)
			)
			(fill no)
			(layer "B.Fab")
		)
		(pad "1" smd custom
			(at 0 -0.4445 180)
			(size 0.1397 0.1397)
			(layers "B.Cu" "B.Mask" "B.Paste")
			(net "TEMP_3_A1")
			(options
				(clearance outline)
				(anchor circle)
			)
			(primitives
				(gr_poly
					(pts
						(arc
							(start -0.1778 0.2794)
							(mid -0.249642 0.249642)
							(end -0.2794 0.1778)
						)
						(arc
							(start -0.2794 -0.1778)
							(mid -0.249642 -0.249642)
							(end -0.1778 -0.2794)
						)
						(arc
							(start 0.1778 -0.2794)
							(mid 0.249642 -0.249642)
							(end 0.2794 -0.1778)
						)
						(arc
							(start 0.2794 0.1778)
							(mid 0.249642 0.249642)
							(end 0.1778 0.2794)
						)
					)
					(width 0)
					(fill yes)
				)
			)
		)
		(pad "2" smd custom
			(at 0 0.4445 180)
			(size 0.1397 0.1397)
			(layers "B.Cu" "B.Mask" "B.Paste")
			(net "GND")
			(options
				(clearance outline)
				(anchor circle)
			)
			(primitives
				(gr_poly
					(pts
						(arc
							(start -0.1778 0.2794)
							(mid -0.249642 0.249642)
							(end -0.2794 0.1778)
						)
						(arc
							(start -0.2794 -0.1778)
							(mid -0.249642 -0.249642)
							(end -0.1778 -0.2794)
						)
						(arc
							(start 0.1778 -0.2794)
							(mid 0.249642 -0.249642)
							(end 0.2794 -0.1778)
						)
						(arc
							(start 0.2794 0.1778)
							(mid 0.249642 0.249642)
							(end 0.1778 0.2794)
						)
					)
					(width 0)
					(fill yes)
				)
			)
		)
	)
	(footprint ""
		(layer "B.Cu")
		(at 53.690012 -135.661654)
		(property "Reference" "R355"
			(at 0 0 0)
			(layer "B.SilkS")
			(hide yes)
			(effects
				(font
					(size 1.27 1.27)
				)
				(justify mirror)
			)
		)
		(property "Value" "4K7R2F-GP"
			(at -0.064008 -3.993896 0)
			(unlocked yes)
			(layer "B.Fab")
			(hide yes)
			(effects
				(font
					(size 1.016 1.016)
					(thickness 0.1524)
				)
				(justify mirror)
			)
		)
		(property "Device Type" "R402H16"
			(at -0.064008 -5.517896 0)
			(unlocked yes)
			(layer "B.Fab")
			(hide yes)
			(effects
				(font
					(size 1.016 1.016)
					(thickness 0.1524)
				)
				(justify mirror)
			)
		)
		(duplicate_pad_numbers_are_jumpers no)
		(fp_line
			(start -0.508 -0.9398)
			(end 0.508 -0.9398)
			(stroke
				(width 0.1524)
				(type default)
			)
			(layer "B.SilkS")
		)
		(fp_line
			(start 0.508 -0.9398)
			(end 0.508 0.9398)
			(stroke
				(width 0.1524)
				(type default)
			)
			(layer "B.SilkS")
		)
		(fp_rect
			(start 0.508 0.9398)
			(end -0.508 -0.9398)
			(stroke
				(width 0)
				(type default)
			)
			(fill no)
			(layer "B.CrtYd")
		)
		(fp_rect
			(start 0.508 0.9398)
			(end -0.508 -0.9398)
			(stroke
				(width 0)
				(type default)
			)
			(fill no)
			(layer "B.Fab")
		)
		(pad "1" smd custom
			(at 0 -0.4445 180)
			(size 0.1397 0.1397)
			(layers "B.Cu" "B.Mask" "B.Paste")
			(net "SLOTID_1")
			(options
				(clearance outline)
				(anchor circle)
			)
			(primitives
				(gr_poly
					(pts
						(arc
							(start -0.1778 0.2794)
							(mid -0.249642 0.249642)
							(end -0.2794 0.1778)
						)
						(arc
							(start -0.2794 -0.1778)
							(mid -0.249642 -0.249642)
							(end -0.1778 -0.2794)
						)
						(arc
							(start 0.1778 -0.2794)
							(mid 0.249642 -0.249642)
							(end 0.2794 -0.1778)
						)
						(arc
							(start 0.2794 0.1778)
							(mid 0.249642 0.249642)
							(end 0.1778 0.2794)
						)
					)
					(width 0)
					(fill yes)
				)
			)
		)
		(pad "2" smd custom
			(at 0 0.4445 180)
			(size 0.1397 0.1397)
			(layers "B.Cu" "B.Mask" "B.Paste")
			(net "GND")
			(options
				(clearance outline)
				(anchor circle)
			)
			(primitives
				(gr_poly
					(pts
						(arc
							(start -0.1778 0.2794)
							(mid -0.249642 0.249642)
							(end -0.2794 0.1778)
						)
						(arc
							(start -0.2794 -0.1778)
							(mid -0.249642 -0.249642)
							(end -0.1778 -0.2794)
						)
						(arc
							(start 0.1778 -0.2794)
							(mid 0.249642 -0.249642)
							(end 0.2794 -0.1778)
						)
						(arc
							(start 0.2794 0.1778)
							(mid 0.249642 0.249642)
							(end 0.1778 0.2794)
						)
					)
					(width 0)
					(fill yes)
				)
			)
		)
	)
	(footprint ""
		(layer "B.Cu")
		(at 225.882454 -53.119274 90)
		(property "Reference" "C154"
			(at 0 0 90)
			(layer "B.SilkS")
			(hide yes)
			(effects
				(font
					(size 1.27 1.27)
				)
				(justify mirror)
			)
		)
		(property "Value" "SC10U16V5KX-7-GP-U"
			(at 0.0762 -6.1214 90)
			(unlocked yes)
			(layer "B.Fab")
			(hide yes)
			(effects
				(font
					(size 1.016 1.016)
					(thickness 0.1524)
				)
				(justify mirror)
			)
		)
		(property "Device Type" "C805H58"
			(at 0.0762 -8.1534 90)
			(unlocked yes)
			(layer "B.Fab")
			(hide yes)
			(effects
				(font
					(size 1.016 1.016)
					(thickness 0.1524)
				)
				(justify mirror)
			)
		)
		(duplicate_pad_numbers_are_jumpers no)
		(fp_line
			(start -0.635 0)
			(end 0.635 0)
			(stroke
				(width 0.508)
				(type default)
			)
			(layer "B.SilkS")
		)
		(fp_rect
			(start 0.9652 1.778)
			(end -0.9652 -1.778)
			(stroke
				(width 0)
				(type default)
			)
			(fill no)
			(layer "B.CrtYd")
		)
		(fp_poly
			(pts
				(xy 0.9652 -1.778) (xy -0.9652 -1.778) (xy -0.9652 1.778) (xy 0.9652 1.778)
			)
			(stroke
				(width 0)
				(type default)
			)
			(fill no)
			(layer "B.Fab")
		)
		(pad "1" smd rect
			(at 0 -0.9652 270)
			(size 1.397 1.143)
			(layers "B.Cu" "B.Mask" "B.Paste")
			(net "P12V_STBY_VIN_PU1")
		)
		(pad "2" smd rect
			(at 0 0.9652 270)
			(size 1.397 1.143)
			(layers "B.Cu" "B.Mask" "B.Paste")
			(net "GND")
		)
	)
	(footprint ""
		(layer "B.Cu")
		(at 60.8838 -140.1826 -90)
		(property "Reference" "R175"
			(at 0 0 90)
			(layer "B.SilkS")
			(hide yes)
			(effects
				(font
					(size 1.27 1.27)
				)
				(justify mirror)
			)
		)
		(property "Value" "0R2J-2-GP"
			(at -0.064008 -3.993896 270)
			(unlocked yes)
			(layer "B.Fab")
			(hide yes)
			(effects
				(font
					(size 1.016 1.016)
					(thickness 0.1524)
				)
				(justify mirror)
			)
		)
		(property "Device Type" "R402H16"
			(at -0.064008 -5.517896 270)
			(unlocked yes)
			(layer "B.Fab")
			(hide yes)
			(effects
				(font
					(size 1.016 1.016)
					(thickness 0.1524)
				)
				(justify mirror)
			)
		)
		(duplicate_pad_numbers_are_jumpers no)
		(fp_line
			(start -0.508 -0.9398)
			(end 0.508 -0.9398)
			(stroke
				(width 0.1524)
				(type default)
			)
			(layer "B.SilkS")
		)
		(fp_line
			(start 0.508 -0.9398)
			(end 0.508 0.9398)
			(stroke
				(width 0.1524)
				(type default)
			)
			(layer "B.SilkS")
		)
		(fp_rect
			(start 0.508 0.9398)
			(end -0.508 -0.9398)
			(stroke
				(width 0)
				(type default)
			)
			(fill no)
			(layer "B.CrtYd")
		)
		(fp_rect
			(start 0.508 0.9398)
			(end -0.508 -0.9398)
			(stroke
				(width 0)
				(type default)
			)
			(fill no)
			(layer "B.Fab")
		)
		(pad "1" smd custom
			(at 0 -0.4445 90)
			(size 0.1397 0.1397)
			(layers "B.Cu" "B.Mask" "B.Paste")
			(net "I2C_M2_2_SCL")
			(options
				(clearance outline)
				(anchor circle)
			)
			(primitives
				(gr_poly
					(pts
						(arc
							(start -0.1778 0.2794)
							(mid -0.249642 0.249642)
							(end -0.2794 0.1778)
						)
						(arc
							(start -0.2794 -0.1778)
							(mid -0.249642 -0.249642)
							(end -0.1778 -0.2794)
						)
						(arc
							(start 0.1778 -0.2794)
							(mid 0.249642 -0.249642)
							(end 0.2794 -0.1778)
						)
						(arc
							(start 0.2794 0.1778)
							(mid 0.249642 0.249642)
							(end 0.1778 0.2794)
						)
					)
					(width 0)
					(fill yes)
				)
			)
		)
		(pad "2" smd custom
			(at 0 0.4445 90)
			(size 0.1397 0.1397)
			(layers "B.Cu" "B.Mask" "B.Paste")
			(net "BMC_SMB9_CLK")
			(options
				(clearance outline)
				(anchor circle)
			)
			(primitives
				(gr_poly
					(pts
						(arc
							(start -0.1778 0.2794)
							(mid -0.249642 0.249642)
							(end -0.2794 0.1778)
						)
						(arc
							(start -0.2794 -0.1778)
							(mid -0.249642 -0.249642)
							(end -0.1778 -0.2794)
						)
						(arc
							(start 0.1778 -0.2794)
							(mid 0.249642 -0.249642)
							(end 0.2794 -0.1778)
						)
						(arc
							(start 0.2794 0.1778)
							(mid 0.249642 0.249642)
							(end 0.1778 0.2794)
						)
					)
					(width 0)
					(fill yes)
				)
			)
		)
	)
	(footprint ""
		(layer "B.Cu")
		(at 50.01006 -143.6624 180)
		(property "Reference" "R363"
			(at 0 0 0)
			(layer "B.SilkS")
			(hide yes)
			(effects
				(font
					(size 1.27 1.27)
				)
				(justify mirror)
			)
		)
		(property "Value" "4K7R2F-GP"
			(at -0.064008 -3.993896 180)
			(unlocked yes)
			(layer "B.Fab")
			(hide yes)
			(effects
				(font
					(size 1.016 1.016)
					(thickness 0.1524)
				)
				(justify mirror)
			)
		)
		(property "Device Type" "R402H16"
			(at -0.064008 -5.517896 180)
			(unlocked yes)
			(layer "B.Fab")
			(hide yes)
			(effects
				(font
					(size 1.016 1.016)
					(thickness 0.1524)
				)
				(justify mirror)
			)
		)
		(duplicate_pad_numbers_are_jumpers no)
		(fp_line
			(start 0.508 -0.9398)
			(end 0.508 0.9398)
			(stroke
				(width 0.1524)
				(type default)
			)
			(layer "B.SilkS")
		)
		(fp_line
			(start -0.508 -0.9398)
			(end 0.508 -0.9398)
			(stroke
				(width 0.1524)
				(type default)
			)
			(layer "B.SilkS")
		)
		(fp_rect
			(start 0.508 0.9398)
			(end -0.508 -0.9398)
			(stroke
				(width 0)
				(type default)
			)
			(fill no)
			(layer "B.CrtYd")
		)
		(fp_rect
			(start 0.508 0.9398)
			(end -0.508 -0.9398)
			(stroke
				(width 0)
				(type default)
			)
			(fill no)
			(layer "B.Fab")
		)
		(pad "1" smd custom
			(at 0 -0.4445)
			(size 0.1397 0.1397)
			(layers "B.Cu" "B.Mask" "B.Paste")
			(net "JTAG_BMC_TRST_N")
			(options
				(clearance outline)
				(anchor circle)
			)
			(primitives
				(gr_poly
					(pts
						(arc
							(start -0.1778 0.2794)
							(mid -0.249642 0.249642)
							(end -0.2794 0.1778)
						)
						(arc
							(start -0.2794 -0.1778)
							(mid -0.249642 -0.249642)
							(end -0.1778 -0.2794)
						)
						(arc
							(start 0.1778 -0.2794)
							(mid 0.249642 -0.249642)
							(end 0.2794 -0.1778)
						)
						(arc
							(start 0.2794 0.1778)
							(mid 0.249642 0.249642)
							(end 0.1778 0.2794)
						)
					)
					(width 0)
					(fill yes)
				)
			)
		)
		(pad "2" smd custom
			(at 0 0.4445)
			(size 0.1397 0.1397)
			(layers "B.Cu" "B.Mask" "B.Paste")
			(net "GND")
			(options
				(clearance outline)
				(anchor circle)
			)
			(primitives
				(gr_poly
					(pts
						(arc
							(start -0.1778 0.2794)
							(mid -0.249642 0.249642)
							(end -0.2794 0.1778)
						)
						(arc
							(start -0.2794 -0.1778)
							(mid -0.249642 -0.249642)
							(end -0.1778 -0.2794)
						)
						(arc
							(start 0.1778 -0.2794)
							(mid 0.249642 -0.249642)
							(end 0.2794 -0.1778)
						)
						(arc
							(start 0.2794 0.1778)
							(mid 0.249642 0.249642)
							(end 0.1778 0.2794)
						)
					)
					(width 0)
					(fill yes)
				)
			)
		)
	)
)
